Altium Designer Pick and Place Locations
C:\Users\<user>\Desktop\WorkNotes\Projects\PTP\Time-Appliance-Project-master\Time-Card\GNSS\UBlox\M2-NEO-M9N\ECAD\Project Outputs for M2_NEO-M9N_MODULE\Pick Place for M2_NEO-M9N_MODULE(845-XXXXX_PCBA_projectname).csv

========================================================================================================================
File Design Information:

Date:       01/07/23
Time:       12:36
Revision:   Not in VersionControl
Variant:    845-XXXXX_PCBA_projectname
Units used: mil

"Designator","Comment","Layer","Footprint","Center-X(mil)","Center-Y(mil)","Rotation","Description"
"Q2","2N7002W","TopLayer","FP-419AB-01-IPC_C","248.031","551.181","90","MOSFET N-CH 60V 115MA SOT-323"
"LED1","Green","TopLayer","led0603","336.156","574.960","90","LED High-Power Uni-Color Green 574nm 2-Pin Chip LED T/R"
"R16","1K_1%_0402","TopLayer","RESC1005X40X25NL05T05","336.704","485.654","270","Chip Resistor, 1 KOhm, +/- 1%, 100 mW, -55 to 155 degC, 0402 (1005 Metric), RoHS, Tape and Reel"
"R15","0_5%_0402","TopLayer","RESC1005X40X25NL05T10","165.354","523.622","90",""
"R14","DNI_0_5%_0402","TopLayer","RESC1005X40X25NL05T10","122.047","523.622","90",""
"R13","0_5%_0402","TopLayer","RESC1005X40X25NL05T10","314.961","271.654","270",""
"R12","0_5%_0402","TopLayer","RESC1005X40X25NL05T10","149.606","271.654","270",""
"R11","10K_5%_0402","TopLayer","RESC1005X40X25LL05T10","401.575","523.622","270",""
"R2","10K_5%_0402","TopLayer","RESC1005X40X25LL05T10","460.630","523.622","270",""
"C7","47uF_6.3V_1206","TopLayer","FP-GRM31C-0_2-e0_3_0_8-IPC_C","681.102","377.953","0","Chip Multilayer Ceramic Capacitors for General Purpose, 1206, 47uF, X5R, 15%, 20%, 6.3V"
"C6","47uF_6.3V_1206","TopLayer","FP-GRM31C-0_2-e0_3_0_8-IPC_C","681.102","468.504","0","Chip Multilayer Ceramic Capacitors for General Purpose, 1206, 47uF, X5R, 15%, 20%, 6.3V"
"R7","0 ohm 0402","TopLayer","r0402","649.606","1417.323","180","RES SMD 0 OHM JUMPER 1/16W 0402"
"Q1","DMG2302UKQ-7","TopLayer","SOT23","439.575","1401.575","90","N-Channel 20 V 2.8A (Ta) 660mW (Ta) Surface Mount SOT-23-3"
"C5","10nF 50V 0402","TopLayer","c0402","255.905","1417.323","180","CAP CER 10000PF 50V X7R 0402"
"U1","NEO-M9N-00B","TopLayer","IC_NEO-M9N","429.134","940.945","90","GNSS module, Flash, TCXO, SAW, LNA, LCC, 12x16 mm Professional Grade"
"TP11","1MM","TopLayer","TP1MM","519.685","606.299","90","Test Point 1MM diameter"
"TP10","1MM","TopLayer","TP1MM","570.866","606.299","90","Test Point 1MM diameter"
"TP9","1MM","TopLayer","TP1MM","464.567","606.299","0","Test Point 1MM diameter"
"TP8","1MM","TopLayer","TP1MM","409.449","606.299","0","Test Point 1MM diameter"
"TP7","1MM","TopLayer","TP1MM","791.339","1185.039","0","Test Point 1MM diameter"
"TP6","1MM","TopLayer","TP1MM","669.291","1476.378","0","Test Point 1MM diameter"
"TP5","1MM","TopLayer","TP1MM","590.551","1287.402","0","Test Point 1MM diameter"
"TP4","1MM","TopLayer","TP1MM","464.567","1279.528","0","Test Point 1MM diameter"
"TP1","1MM","TopLayer","TP1MM","696.850","1271.653","0","Test Point 1MM diameter"
"R8","0 ohm 0402","TopLayer","r0402","204.724","271.653","270","RES SMD 0 OHM JUMPER 1/16W 0402"
"R5","0 ohm 0402","TopLayer","r0402","259.842","271.653","270","RES SMD 0 OHM JUMPER 1/16W 0402"
"R4","10 OHM 1/4W 0603","TopLayer","r0603","263.779","1354.331","180","Res Surge Chip Thick Film 0603 10 Ohm 1% 1/4W ±200ppm/°C Molded Paper T/R"
"R3","1K_1%_0402","TopLayer","RESC1005X40X25NL05T05","472.441","417.323","0","Chip Resistor, 1 KOhm, +/- 1%, 100 mW, -55 to 155 degC, 0402 (1005 Metric), RoHS, Tape and Reel"
"R1","0 ohm 0402","TopLayer","r0402","393.701","1275.591","180","RES SMD 0 OHM JUMPER 1/16W 0402"
"LED2","Green","TopLayer","led0603","472.441","346.457","0","LED High-Power Uni-Color Green 574nm 2-Pin Chip LED T/R"
"L1","27nH 350mA 0.46ohm 0402","TopLayer","FP-LQG15HH_02-IPC_C","169.291","1417.323","180","Multilayer type RF Inductor 27nH ±5% 0.46O 350mA 0402"
"J2","U.FL-R-SMT-1(10)","TopLayer","FP-U_FL-R-SMT-1_10-MFG","133.858","1540.846","180","CONN U.FL RCPT STR 50 OHM SMD"
"J1","OCPTAP_M2_FINGERS","TopLayer","OCPTAP_M2_FINGERS","433.071","55.118","0",""
"C4","47pF 50V 0402","TopLayer","c0402","153.543","1350.394","270","0402 47 pF 50 V ±5 % Tolerance NP0 SMT Multilayer Ceramic Capacitor"
"C3","10nF 50V 0402","TopLayer","c0402","685.039","535.433","180","CAP CER 10000PF 50V X7R 0402"
"C2","100nF 10V 0402","TopLayer","c0402","685.039","582.677","180","CL05 Series 0.1 uF 10 V ±10 % Tolerance X7R SMT Multilayer Ceramic Capacitor"
"C1","1uF 6V3 0402","TopLayer","c0402","685.039","629.921","180","0402 1 uF 6.3 V ±10% Tolerance X7R Multilayer Ceramic Capacitor"
